(kicad_pcb
	(version 20260206)
	(generator "pcbnew")
	(generator_version "10.0")
	(general
		(thickness 1.6)
		(legacy_teardrops no)
	)
	(paper "A4")
	(title_block
		(title "01162023_DA0F0TEBIF0_F0T_Expander_BD_F_brd_V02_OCP.brd")
		(comment 1 "Grand Teton / footprints 5118-5124 of 9728")
	)
	(layers
		(0 "F.Cu" signal "TOP")
		(4 "In1.Cu" signal "GND")
		(6 "In2.Cu" signal "VCC")
		(8 "In3.Cu" signal "VCC1")
		(10 "In4.Cu" signal "GND1")
		(12 "In5.Cu" signal "IN1")
		(14 "In6.Cu" signal "GND2")
		(16 "In7.Cu" signal "IN2")
		(18 "In8.Cu" signal "GND3")
		(20 "In9.Cu" signal "IN3")
		(22 "In10.Cu" signal "GND4")
		(24 "In11.Cu" signal "IN4")
		(26 "In12.Cu" signal "GND5")
		(28 "In13.Cu" signal "IN5")
		(30 "In14.Cu" signal "GND6")
		(32 "In15.Cu" signal "IN6")
		(34 "In16.Cu" signal "GND7")
		(2 "B.Cu" signal "BOTTOM")
		(9 "F.Adhes" user "F.Adhesive")
		(11 "B.Adhes" user "B.Adhesive")
		(13 "F.Paste" user "Package Geometry/Pastemask Top")
		(15 "B.Paste" user "Package Geometry/Pastemask Bottom")
		(5 "F.SilkS" user "Ref Des/Silkscreen Top")
		(7 "B.SilkS" user "Ref Des/Silkscreen Bottom")
		(1 "F.Mask" user "Board Geometry/Soldermask Top")
		(3 "B.Mask" user "Board Geometry/Soldermask Bottom")
		(17 "Dwgs.User" user "User.Drawings")
		(19 "Cmts.User" user "User.Comments")
		(21 "Eco1.User" user "User.Eco1")
		(23 "Eco2.User" user "User.Eco2")
		(25 "Edge.Cuts" user "Board Geometry/Outline")
		(27 "Margin" user)
		(31 "F.CrtYd" user "Package Geometry/Place Bound Top")
		(29 "B.CrtYd" user "Package Geometry/Place Bound Bottom")
		(35 "F.Fab" user "Ref Des/Assembly Top")
		(33 "B.Fab" user "Ref Des/Assembly Bottom")
	)
	(footprint ""
		(layer "F.Cu")
		(at 327.533 -218.313)
		(property "Reference" "R4163"
			(at 0 0 0)
			(layer "F.SilkS")
			(hide yes)
			(effects
				(font
					(size 1.27 1.27)
				)
			)
		)
		(property "Value" ""
			(at 0 0 0)
			(layer "F.Fab")
			(effects
				(font
					(size 1.27 1.27)
				)
			)
		)
		(duplicate_pad_numbers_are_jumpers no)
		(fp_line
			(start -0.7874 -0.4064)
			(end 0.7874 -0.4064)
			(stroke
				(width 0.1524)
				(type default)
			)
			(layer "F.SilkS")
		)
		(fp_line
			(start -0.7874 0.4064)
			(end -0.7874 -0.4064)
			(stroke
				(width 0.1524)
				(type default)
			)
			(layer "F.SilkS")
		)
		(fp_line
			(start 0.7874 -0.4064)
			(end 0.7874 0.4064)
			(stroke
				(width 0.1524)
				(type default)
			)
			(layer "F.SilkS")
		)
		(fp_line
			(start 0.7874 0.4064)
			(end -0.7874 0.4064)
			(stroke
				(width 0.1524)
				(type default)
			)
			(layer "F.SilkS")
		)
		(fp_line
			(start -0.67945 -0.305054)
			(end -0.12065 -0.305054)
			(stroke
				(width 0.1)
				(type default)
			)
			(layer "F.Fab")
		)
		(fp_line
			(start -0.67945 0.3048)
			(end -0.67945 -0.305054)
			(stroke
				(width 0.1)
				(type default)
			)
			(layer "F.Fab")
		)
		(fp_line
			(start -0.12065 -0.305054)
			(end -0.12065 -0.2794)
			(stroke
				(width 0.1)
				(type default)
			)
			(layer "F.Fab")
		)
		(fp_line
			(start -0.12065 -0.2794)
			(end 0.12065 -0.2794)
			(stroke
				(width 0.1)
				(type default)
			)
			(layer "F.Fab")
		)
		(fp_line
			(start -0.12065 0.2794)
			(end -0.12065 0.3048)
			(stroke
				(width 0.1)
				(type default)
			)
			(layer "F.Fab")
		)
		(fp_line
			(start -0.12065 0.3048)
			(end -0.67945 0.3048)
			(stroke
				(width 0.1)
				(type default)
			)
			(layer "F.Fab")
		)
		(fp_line
			(start 0.120396 0.2794)
			(end -0.12065 0.2794)
			(stroke
				(width 0.1)
				(type default)
			)
			(layer "F.Fab")
		)
		(fp_line
			(start 0.120396 0.3048)
			(end 0.120396 0.2794)
			(stroke
				(width 0.1)
				(type default)
			)
			(layer "F.Fab")
		)
		(fp_line
			(start 0.12065 -0.3048)
			(end 0.67945 -0.3048)
			(stroke
				(width 0.1)
				(type default)
			)
			(layer "F.Fab")
		)
		(fp_line
			(start 0.12065 -0.2794)
			(end 0.12065 -0.3048)
			(stroke
				(width 0.1)
				(type default)
			)
			(layer "F.Fab")
		)
		(fp_line
			(start 0.67945 -0.3048)
			(end 0.67945 0.3048)
			(stroke
				(width 0.1)
				(type default)
			)
			(layer "F.Fab")
		)
		(fp_line
			(start 0.67945 0.3048)
			(end 0.120396 0.3048)
			(stroke
				(width 0.1)
				(type default)
			)
			(layer "F.Fab")
		)
		(pad "1" smd circle
			(at -0.40005 0)
			(size 0 0)
			(layers "F.Cu" "F.Mask" "F.Paste")
			(net "PRSNT_NIC6_FPGA_R_N")
		)
		(pad "2" smd circle
			(at 0.40005 0)
			(size 0 0)
			(layers "F.Cu" "F.Mask" "F.Paste")
			(net "PRSNT_NIC6_FPGA_N")
		)
	)
	(footprint ""
		(layer "F.Cu")
		(at 229.594664 -207.02016 -90)
		(property "Reference" "R1506"
			(at 0 0 270)
			(layer "F.SilkS")
			(hide yes)
			(effects
				(font
					(size 1.27 1.27)
				)
			)
		)
		(property "Value" ""
			(at 0 0 270)
			(layer "F.Fab")
			(effects
				(font
					(size 1.27 1.27)
				)
			)
		)
		(duplicate_pad_numbers_are_jumpers no)
		(fp_line
			(start -0.7874 0.4064)
			(end -0.7874 -0.4064)
			(stroke
				(width 0.1524)
				(type default)
			)
			(layer "F.SilkS")
		)
		(fp_line
			(start 0.7874 0.4064)
			(end -0.7874 0.4064)
			(stroke
				(width 0.1524)
				(type default)
			)
			(layer "F.SilkS")
		)
		(fp_line
			(start -0.7874 -0.4064)
			(end 0.7874 -0.4064)
			(stroke
				(width 0.1524)
				(type default)
			)
			(layer "F.SilkS")
		)
		(fp_line
			(start 0.7874 -0.4064)
			(end 0.7874 0.4064)
			(stroke
				(width 0.1524)
				(type default)
			)
			(layer "F.SilkS")
		)
		(fp_line
			(start -0.67945 0.3048)
			(end -0.67945 -0.305054)
			(stroke
				(width 0.1)
				(type default)
			)
			(layer "F.Fab")
		)
		(fp_line
			(start -0.12065 0.3048)
			(end -0.67945 0.3048)
			(stroke
				(width 0.1)
				(type default)
			)
			(layer "F.Fab")
		)
		(fp_line
			(start 0.120396 0.3048)
			(end 0.120396 0.2794)
			(stroke
				(width 0.1)
				(type default)
			)
			(layer "F.Fab")
		)
		(fp_line
			(start 0.67945 0.3048)
			(end 0.120396 0.3048)
			(stroke
				(width 0.1)
				(type default)
			)
			(layer "F.Fab")
		)
		(fp_line
			(start -0.12065 0.2794)
			(end -0.12065 0.3048)
			(stroke
				(width 0.1)
				(type default)
			)
			(layer "F.Fab")
		)
		(fp_line
			(start 0.120396 0.2794)
			(end -0.12065 0.2794)
			(stroke
				(width 0.1)
				(type default)
			)
			(layer "F.Fab")
		)
		(fp_line
			(start -0.12065 -0.2794)
			(end 0.12065 -0.2794)
			(stroke
				(width 0.1)
				(type default)
			)
			(layer "F.Fab")
		)
		(fp_line
			(start 0.12065 -0.2794)
			(end 0.12065 -0.3048)
			(stroke
				(width 0.1)
				(type default)
			)
			(layer "F.Fab")
		)
		(fp_line
			(start 0.12065 -0.3048)
			(end 0.67945 -0.3048)
			(stroke
				(width 0.1)
				(type default)
			)
			(layer "F.Fab")
		)
		(fp_line
			(start 0.67945 -0.3048)
			(end 0.67945 0.3048)
			(stroke
				(width 0.1)
				(type default)
			)
			(layer "F.Fab")
		)
		(fp_line
			(start -0.67945 -0.305054)
			(end -0.12065 -0.305054)
			(stroke
				(width 0.1)
				(type default)
			)
			(layer "F.Fab")
		)
		(fp_line
			(start -0.12065 -0.305054)
			(end -0.12065 -0.2794)
			(stroke
				(width 0.1)
				(type default)
			)
			(layer "F.Fab")
		)
		(pad "1" smd circle
			(at -0.40005 0 270)
			(size 0 0)
			(layers "F.Cu" "F.Mask" "F.Paste")
			(net "SPI_BIC1_CS0_N")
		)
		(pad "2" smd circle
			(at 0.40005 0 270)
			(size 0 0)
			(layers "F.Cu" "F.Mask" "F.Paste")
			(net "P3V3_AUX")
		)
	)
	(footprint ""
		(layer "F.Cu")
		(at 28.04922 -300.197012 -90)
		(property "Reference" "C3038"
			(at 0 0 270)
			(layer "F.SilkS")
			(hide yes)
			(effects
				(font
					(size 1.27 1.27)
				)
			)
		)
		(property "Value" ""
			(at 0 0 270)
			(layer "F.Fab")
			(effects
				(font
					(size 1.27 1.27)
				)
			)
		)
		(duplicate_pad_numbers_are_jumpers no)
		(fp_line
			(start -0.299974 0.150114)
			(end -0.299974 -0.150114)
			(stroke
				(width 0.1)
				(type default)
			)
			(layer "F.Fab")
		)
		(fp_line
			(start 0.299974 0.150114)
			(end -0.299974 0.150114)
			(stroke
				(width 0.1)
				(type default)
			)
			(layer "F.Fab")
		)
		(fp_line
			(start -0.299974 -0.150114)
			(end 0.299974 -0.150114)
			(stroke
				(width 0.1)
				(type default)
			)
			(layer "F.Fab")
		)
		(fp_line
			(start 0.299974 -0.150114)
			(end 0.299974 0.150114)
			(stroke
				(width 0.1)
				(type default)
			)
			(layer "F.Fab")
		)
		(pad "1" smd rect
			(at -0.2667 0 270)
			(size 0.3048 0.381)
			(layers "F.Cu" "F.Mask" "F.Paste")
			(net "P1V8_PLL0_PEX0")
		)
		(pad "2" smd rect
			(at 0.2667 0 270)
			(size 0.3048 0.381)
			(layers "F.Cu" "F.Mask" "F.Paste")
			(net "GND")
		)
	)
	(footprint ""
		(layer "F.Cu")
		(at 95.906844 -189.3062 180)
		(property "Reference" "R6628"
			(at 0 0 180)
			(layer "F.SilkS")
			(hide yes)
			(effects
				(font
					(size 1.27 1.27)
				)
			)
		)
		(property "Value" ""
			(at 0 0 180)
			(layer "F.Fab")
			(effects
				(font
					(size 1.27 1.27)
				)
			)
		)
		(duplicate_pad_numbers_are_jumpers no)
		(fp_line
			(start 0.7874 0.4064)
			(end -0.7874 0.4064)
			(stroke
				(width 0.1524)
				(type default)
			)
			(layer "F.SilkS")
		)
		(fp_line
			(start 0.7874 -0.4064)
			(end 0.7874 0.4064)
			(stroke
				(width 0.1524)
				(type default)
			)
			(layer "F.SilkS")
		)
		(fp_line
			(start -0.7874 0.4064)
			(end -0.7874 -0.4064)
			(stroke
				(width 0.1524)
				(type default)
			)
			(layer "F.SilkS")
		)
		(fp_line
			(start -0.7874 -0.4064)
			(end 0.7874 -0.4064)
			(stroke
				(width 0.1524)
				(type default)
			)
			(layer "F.SilkS")
		)
		(fp_line
			(start 0.67945 0.3048)
			(end 0.120396 0.3048)
			(stroke
				(width 0.1)
				(type default)
			)
			(layer "F.Fab")
		)
		(fp_line
			(start 0.67945 -0.3048)
			(end 0.67945 0.3048)
			(stroke
				(width 0.1)
				(type default)
			)
			(layer "F.Fab")
		)
		(fp_line
			(start 0.12065 -0.2794)
			(end 0.12065 -0.3048)
			(stroke
				(width 0.1)
				(type default)
			)
			(layer "F.Fab")
		)
		(fp_line
			(start 0.12065 -0.3048)
			(end 0.67945 -0.3048)
			(stroke
				(width 0.1)
				(type default)
			)
			(layer "F.Fab")
		)
		(fp_line
			(start 0.120396 0.3048)
			(end 0.120396 0.2794)
			(stroke
				(width 0.1)
				(type default)
			)
			(layer "F.Fab")
		)
		(fp_line
			(start 0.120396 0.2794)
			(end -0.12065 0.2794)
			(stroke
				(width 0.1)
				(type default)
			)
			(layer "F.Fab")
		)
		(fp_line
			(start -0.12065 0.3048)
			(end -0.67945 0.3048)
			(stroke
				(width 0.1)
				(type default)
			)
			(layer "F.Fab")
		)
		(fp_line
			(start -0.12065 0.2794)
			(end -0.12065 0.3048)
			(stroke
				(width 0.1)
				(type default)
			)
			(layer "F.Fab")
		)
		(fp_line
			(start -0.12065 -0.2794)
			(end 0.12065 -0.2794)
			(stroke
				(width 0.1)
				(type default)
			)
			(layer "F.Fab")
		)
		(fp_line
			(start -0.12065 -0.305054)
			(end -0.12065 -0.2794)
			(stroke
				(width 0.1)
				(type default)
			)
			(layer "F.Fab")
		)
		(fp_line
			(start -0.67945 0.3048)
			(end -0.67945 -0.305054)
			(stroke
				(width 0.1)
				(type default)
			)
			(layer "F.Fab")
		)
		(fp_line
			(start -0.67945 -0.305054)
			(end -0.12065 -0.305054)
			(stroke
				(width 0.1)
				(type default)
			)
			(layer "F.Fab")
		)
		(pad "1" smd circle
			(at -0.40005 0 180)
			(size 0 0)
			(layers "F.Cu" "F.Mask" "F.Paste")
			(net "UART_PEX2_CLI_CP2108_RX")
		)
		(pad "2" smd circle
			(at 0.40005 0 180)
			(size 0 0)
			(layers "F.Cu" "F.Mask" "F.Paste")
			(net "UART_PEX2_CLI_R_RX")
		)
	)
	(footprint ""
		(layer "F.Cu")
		(at 374.567958 -51.019456)
		(property "Reference" "PC411"
			(at 0 0 0)
			(layer "F.SilkS")
			(hide yes)
			(effects
				(font
					(size 1.27 1.27)
				)
			)
		)
		(property "Value" ""
			(at 0 0 0)
			(layer "F.Fab")
			(effects
				(font
					(size 1.27 1.27)
				)
			)
		)
		(duplicate_pad_numbers_are_jumpers no)
		(fp_line
			(start -0.7874 -0.4064)
			(end 0.7874 -0.4064)
			(stroke
				(width 0.1524)
				(type default)
			)
			(layer "F.SilkS")
		)
		(fp_line
			(start -0.7874 0.4064)
			(end -0.7874 -0.4064)
			(stroke
				(width 0.1524)
				(type default)
			)
			(layer "F.SilkS")
		)
		(fp_line
			(start 0.7874 -0.4064)
			(end 0.7874 0.4064)
			(stroke
				(width 0.1524)
				(type default)
			)
			(layer "F.SilkS")
		)
		(fp_line
			(start 0.7874 0.4064)
			(end -0.7874 0.4064)
			(stroke
				(width 0.1524)
				(type default)
			)
			(layer "F.SilkS")
		)
		(fp_line
			(start -0.67945 -0.305054)
			(end -0.12065 -0.305054)
			(stroke
				(width 0.1)
				(type default)
			)
			(layer "F.Fab")
		)
		(fp_line
			(start -0.67945 0.3048)
			(end -0.67945 -0.305054)
			(stroke
				(width 0.1)
				(type default)
			)
			(layer "F.Fab")
		)
		(fp_line
			(start -0.12065 -0.305054)
			(end -0.12065 -0.2794)
			(stroke
				(width 0.1)
				(type default)
			)
			(layer "F.Fab")
		)
		(fp_line
			(start -0.12065 -0.2794)
			(end 0.12065 -0.2794)
			(stroke
				(width 0.1)
				(type default)
			)
			(layer "F.Fab")
		)
		(fp_line
			(start -0.12065 0.2794)
			(end -0.12065 0.3048)
			(stroke
				(width 0.1)
				(type default)
			)
			(layer "F.Fab")
		)
		(fp_line
			(start -0.12065 0.3048)
			(end -0.67945 0.3048)
			(stroke
				(width 0.1)
				(type default)
			)
			(layer "F.Fab")
		)
		(fp_line
			(start 0.120396 0.2794)
			(end -0.12065 0.2794)
			(stroke
				(width 0.1)
				(type default)
			)
			(layer "F.Fab")
		)
		(fp_line
			(start 0.120396 0.3048)
			(end 0.120396 0.2794)
			(stroke
				(width 0.1)
				(type default)
			)
			(layer "F.Fab")
		)
		(fp_line
			(start 0.12065 -0.3048)
			(end 0.67945 -0.3048)
			(stroke
				(width 0.1)
				(type default)
			)
			(layer "F.Fab")
		)
		(fp_line
			(start 0.12065 -0.2794)
			(end 0.12065 -0.3048)
			(stroke
				(width 0.1)
				(type default)
			)
			(layer "F.Fab")
		)
		(fp_line
			(start 0.67945 -0.3048)
			(end 0.67945 0.3048)
			(stroke
				(width 0.1)
				(type default)
			)
			(layer "F.Fab")
		)
		(fp_line
			(start 0.67945 0.3048)
			(end 0.120396 0.3048)
			(stroke
				(width 0.1)
				(type default)
			)
			(layer "F.Fab")
		)
		(pad "1" smd circle
			(at -0.40005 0)
			(size 0 0)
			(layers "F.Cu" "F.Mask" "F.Paste")
			(net "P12V_SSD12_SS")
		)
		(pad "2" smd circle
			(at 0.40005 0)
			(size 0 0)
			(layers "F.Cu" "F.Mask" "F.Paste")
			(net "GND")
		)
	)
	(footprint ""
		(layer "F.Cu")
		(at 413.723328 -241.83848)
		(property "Reference" "J66"
			(at -7.126986 0.264668 0)
			(unlocked yes)
			(layer "F.SilkS")
			(effects
				(font
					(size 0.7874 0.5842)
					(thickness 0.1524)
				)
				(justify left)
			)
		)
		(property "Value" ""
			(at 0 0 0)
			(layer "F.Fab")
			(effects
				(font
					(size 1.27 1.27)
				)
			)
		)
		(duplicate_pad_numbers_are_jumpers no)
		(fp_line
			(start -1.27 -3.81)
			(end 1.27 -3.81)
			(stroke
				(width 0.1524)
				(type default)
			)
			(layer "F.SilkS")
		)
		(fp_line
			(start -1.27 -0.7747)
			(end -1.27 -3.81)
			(stroke
				(width 0.1524)
				(type default)
			)
			(layer "F.SilkS")
		)
		(fp_line
			(start -1.27 3.81)
			(end -1.27 0.7747)
			(stroke
				(width 0.1524)
				(type default)
			)
			(layer "F.SilkS")
		)
		(fp_line
			(start 1.27 -3.81)
			(end 1.27 -3.3147)
			(stroke
				(width 0.1524)
				(type default)
			)
			(layer "F.SilkS")
		)
		(fp_line
			(start 1.27 -1.7653)
			(end 1.27 1.7653)
			(stroke
				(width 0.1524)
				(type default)
			)
			(layer "F.SilkS")
		)
		(fp_line
			(start 1.27 3.3147)
			(end 1.27 3.81)
			(stroke
				(width 0.1524)
				(type default)
			)
			(layer "F.SilkS")
		)
		(fp_line
			(start 1.27 3.81)
			(end -1.27 3.81)
			(stroke
				(width 0.1524)
				(type default)
			)
			(layer "F.SilkS")
		)
		(fp_poly
			(pts
				(xy 4.3942 -3.048) (xy 4.3942 -2.032) (xy 3.3782 -2.54)
			)
			(stroke
				(width 0)
				(type default)
			)
			(fill yes)
			(layer "F.SilkS")
		)
		(fp_line
			(start -1.27 -3.81)
			(end -1.27 3.81)
			(stroke
				(width 0.1)
				(type default)
			)
			(layer "F.Fab")
		)
		(fp_line
			(start -1.27 3.81)
			(end 1.27 3.81)
			(stroke
				(width 0.1)
				(type default)
			)
			(layer "F.Fab")
		)
		(fp_line
			(start 1.27 -3.81)
			(end -1.27 -3.81)
			(stroke
				(width 0.1)
				(type default)
			)
			(layer "F.Fab")
		)
		(fp_line
			(start 1.27 3.81)
			(end 1.27 -3.81)
			(stroke
				(width 0.1)
				(type default)
			)
			(layer "F.Fab")
		)
		(fp_poly
			(pts
				(xy 4.3942 -3.048) (xy 4.3942 -2.032) (xy 3.3782 -2.54)
			)
			(stroke
				(width 0)
				(type default)
			)
			(fill yes)
			(layer "F.Fab")
		)
		(fp_text user "3"
			(at 3.921252 2.54 90)
			(unlocked yes)
			(layer "F.SilkS")
			(effects
				(font
					(size 0.7874 0.5842)
					(thickness 0.1524)
				)
			)
		)
		(fp_text user "3"
			(at 3.921252 2.54 90)
			(unlocked yes)
			(layer "F.Fab")
			(effects
				(font
					(size 0.7874 0.5842)
					(thickness 0.1524)
				)
			)
		)
		(pad "1" smd rect
			(at 1.459992 -2.54 90)
			(size 1.27 3.429)
			(layers "F.Cu" "F.Mask" "F.Paste")
			(net "GND")
		)
		(pad "2" smd rect
			(at -1.459992 0 90)
			(size 1.27 3.429)
			(layers "F.Cu" "F.Mask" "F.Paste")
			(net "UART_PEX2_SDB_BUF_R1_TX")
		)
		(pad "3" smd rect
			(at 1.459992 2.54 90)
			(size 1.27 3.429)
			(layers "F.Cu" "F.Mask" "F.Paste")
			(net "UART_PEX2_SDB_R1_RX")
		)
	)
	(footprint ""
		(layer "F.Cu")
		(at 154.882596 -140.85697)
		(property "Reference" "R136"
			(at 0 0 0)
			(layer "F.SilkS")
			(hide yes)
			(effects
				(font
					(size 1.27 1.27)
				)
			)
		)
		(property "Value" ""
			(at 0 0 0)
			(layer "F.Fab")
			(effects
				(font
					(size 1.27 1.27)
				)
			)
		)
		(duplicate_pad_numbers_are_jumpers no)
		(fp_line
			(start -0.7874 -0.4064)
			(end 0.7874 -0.4064)
			(stroke
				(width 0.1524)
				(type default)
			)
			(layer "F.SilkS")
		)
		(fp_line
			(start -0.7874 0.4064)
			(end -0.7874 -0.4064)
			(stroke
				(width 0.1524)
				(type default)
			)
			(layer "F.SilkS")
		)
		(fp_line
			(start 0.7874 -0.4064)
			(end 0.7874 0.4064)
			(stroke
				(width 0.1524)
				(type default)
			)
			(layer "F.SilkS")
		)
		(fp_line
			(start 0.7874 0.4064)
			(end -0.7874 0.4064)
			(stroke
				(width 0.1524)
				(type default)
			)
			(layer "F.SilkS")
		)
		(fp_line
			(start -0.67945 -0.305054)
			(end -0.12065 -0.305054)
			(stroke
				(width 0.1)
				(type default)
			)
			(layer "F.Fab")
		)
		(fp_line
			(start -0.67945 0.3048)
			(end -0.67945 -0.305054)
			(stroke
				(width 0.1)
				(type default)
			)
			(layer "F.Fab")
		)
		(fp_line
			(start -0.12065 -0.305054)
			(end -0.12065 -0.2794)
			(stroke
				(width 0.1)
				(type default)
			)
			(layer "F.Fab")
		)
		(fp_line
			(start -0.12065 -0.2794)
			(end 0.12065 -0.2794)
			(stroke
				(width 0.1)
				(type default)
			)
			(layer "F.Fab")
		)
		(fp_line
			(start -0.12065 0.2794)
			(end -0.12065 0.3048)
			(stroke
				(width 0.1)
				(type default)
			)
			(layer "F.Fab")
		)
		(fp_line
			(start -0.12065 0.3048)
			(end -0.67945 0.3048)
			(stroke
				(width 0.1)
				(type default)
			)
			(layer "F.Fab")
		)
		(fp_line
			(start 0.120396 0.2794)
			(end -0.12065 0.2794)
			(stroke
				(width 0.1)
				(type default)
			)
			(layer "F.Fab")
		)
		(fp_line
			(start 0.120396 0.3048)
			(end 0.120396 0.2794)
			(stroke
				(width 0.1)
				(type default)
			)
			(layer "F.Fab")
		)
		(fp_line
			(start 0.12065 -0.3048)
			(end 0.67945 -0.3048)
			(stroke
				(width 0.1)
				(type default)
			)
			(layer "F.Fab")
		)
		(fp_line
			(start 0.12065 -0.2794)
			(end 0.12065 -0.3048)
			(stroke
				(width 0.1)
				(type default)
			)
			(layer "F.Fab")
		)
		(fp_line
			(start 0.67945 -0.3048)
			(end 0.67945 0.3048)
			(stroke
				(width 0.1)
				(type default)
			)
			(layer "F.Fab")
		)
		(fp_line
			(start 0.67945 0.3048)
			(end 0.120396 0.3048)
			(stroke
				(width 0.1)
				(type default)
			)
			(layer "F.Fab")
		)
		(pad "1" smd circle
			(at -0.40005 0)
			(size 0 0)
			(layers "F.Cu" "F.Mask" "F.Paste")
			(net "NIC2_BIF2_N")
		)
		(pad "2" smd circle
			(at 0.40005 0)
			(size 0 0)
			(layers "F.Cu" "F.Mask" "F.Paste")
			(net "GND")
		)
	)
)
